(kicad_pcb
	(version 20260206)
	(generator "pcbnew")
	(generator_version "10.0")
	(general
		(thickness 1.6)
		(legacy_teardrops no)
	)
	(paper "A4")
	(title_block
		(title "12092022_DA0F0TFB6D0_F0T_FAN_BOARD_MP5048_D_brd_v02_OCP.brd")
		(comment 1 "Grand Teton / footprints 16-20 of 924")
	)
	(layers
		(0 "F.Cu" signal "TOP")
		(4 "In1.Cu" signal "GND")
		(6 "In2.Cu" signal "IN1")
		(8 "In3.Cu" signal "IN2")
		(10 "In4.Cu" signal "GND1")
		(2 "B.Cu" signal "BOTTOM")
		(9 "F.Adhes" user "F.Adhesive")
		(11 "B.Adhes" user "B.Adhesive")
		(13 "F.Paste" user "Package Geometry/Pastemask Top")
		(15 "B.Paste" user "Package Geometry/Pastemask Bottom")
		(5 "F.SilkS" user "Ref Des/Silkscreen Top")
		(7 "B.SilkS" user "Ref Des/Silkscreen Bottom")
		(1 "F.Mask" user "Board Geometry/Soldermask Top")
		(3 "B.Mask" user "Board Geometry/Soldermask Bottom")
		(17 "Dwgs.User" user "User.Drawings")
		(19 "Cmts.User" user "User.Comments")
		(21 "Eco1.User" user "User.Eco1")
		(23 "Eco2.User" user "User.Eco2")
		(25 "Edge.Cuts" user "Board Geometry/Outline")
		(27 "Margin" user)
		(31 "F.CrtYd" user "Package Geometry/Place Bound Top")
		(29 "B.CrtYd" user "Package Geometry/Place Bound Bottom")
		(35 "F.Fab" user "Ref Des/Assembly Top")
		(33 "B.Fab" user "Ref Des/Assembly Bottom")
	)
	(footprint ""
		(layer "F.Cu")
		(at 18.669 -289.179)
		(property "Reference" "R5322"
			(at 0 0 0)
			(layer "F.SilkS")
			(hide yes)
			(effects
				(font
					(size 1.27 1.27)
				)
			)
		)
		(property "Value" ""
			(at 0 0 0)
			(layer "F.Fab")
			(effects
				(font
					(size 1.27 1.27)
				)
			)
		)
		(duplicate_pad_numbers_are_jumpers no)
		(fp_line
			(start -0.7874 -0.4064)
			(end 0.7874 -0.4064)
			(stroke
				(width 0.1524)
				(type default)
			)
			(layer "F.SilkS")
		)
		(fp_line
			(start -0.7874 0.4064)
			(end -0.7874 -0.4064)
			(stroke
				(width 0.1524)
				(type default)
			)
			(layer "F.SilkS")
		)
		(fp_line
			(start 0.7874 -0.4064)
			(end 0.7874 0.4064)
			(stroke
				(width 0.1524)
				(type default)
			)
			(layer "F.SilkS")
		)
		(fp_line
			(start 0.7874 0.4064)
			(end -0.7874 0.4064)
			(stroke
				(width 0.1524)
				(type default)
			)
			(layer "F.SilkS")
		)
		(fp_line
			(start -0.67945 -0.305054)
			(end -0.12065 -0.305054)
			(stroke
				(width 0.1)
				(type default)
			)
			(layer "F.Fab")
		)
		(fp_line
			(start -0.67945 0.3048)
			(end -0.67945 -0.305054)
			(stroke
				(width 0.1)
				(type default)
			)
			(layer "F.Fab")
		)
		(fp_line
			(start -0.12065 -0.305054)
			(end -0.12065 -0.2794)
			(stroke
				(width 0.1)
				(type default)
			)
			(layer "F.Fab")
		)
		(fp_line
			(start -0.12065 -0.2794)
			(end 0.12065 -0.2794)
			(stroke
				(width 0.1)
				(type default)
			)
			(layer "F.Fab")
		)
		(fp_line
			(start -0.12065 0.2794)
			(end -0.12065 0.3048)
			(stroke
				(width 0.1)
				(type default)
			)
			(layer "F.Fab")
		)
		(fp_line
			(start -0.12065 0.3048)
			(end -0.67945 0.3048)
			(stroke
				(width 0.1)
				(type default)
			)
			(layer "F.Fab")
		)
		(fp_line
			(start 0.120396 0.2794)
			(end -0.12065 0.2794)
			(stroke
				(width 0.1)
				(type default)
			)
			(layer "F.Fab")
		)
		(fp_line
			(start 0.120396 0.3048)
			(end 0.120396 0.2794)
			(stroke
				(width 0.1)
				(type default)
			)
			(layer "F.Fab")
		)
		(fp_line
			(start 0.12065 -0.3048)
			(end 0.67945 -0.3048)
			(stroke
				(width 0.1)
				(type default)
			)
			(layer "F.Fab")
		)
		(fp_line
			(start 0.12065 -0.2794)
			(end 0.12065 -0.3048)
			(stroke
				(width 0.1)
				(type default)
			)
			(layer "F.Fab")
		)
		(fp_line
			(start 0.67945 -0.3048)
			(end 0.67945 0.3048)
			(stroke
				(width 0.1)
				(type default)
			)
			(layer "F.Fab")
		)
		(fp_line
			(start 0.67945 0.3048)
			(end 0.120396 0.3048)
			(stroke
				(width 0.1)
				(type default)
			)
			(layer "F.Fab")
		)
		(pad "1" smd rect
			(at -0.40005 0 180)
			(size 0.4572 0.508)
			(layers "F.Cu" "F.Mask" "F.Paste")
			(net "FAN_7_TACH_IL_R")
		)
		(pad "2" smd rect
			(at 0.40005 0 180)
			(size 0.4572 0.508)
			(layers "F.Cu" "F.Mask" "F.Paste")
			(net "FAN_7_TACH_IL")
		)
	)
	(footprint ""
		(layer "F.Cu")
		(at 16.520922 -19.136868)
		(property "Reference" "C2015"
			(at 0 0 0)
			(layer "F.SilkS")
			(hide yes)
			(effects
				(font
					(size 1.27 1.27)
				)
			)
		)
		(property "Value" ""
			(at 0 0 0)
			(layer "F.Fab")
			(effects
				(font
					(size 1.27 1.27)
				)
			)
		)
		(duplicate_pad_numbers_are_jumpers no)
		(fp_line
			(start -0.7874 -0.4064)
			(end 0.7874 -0.4064)
			(stroke
				(width 0.1524)
				(type default)
			)
			(layer "F.SilkS")
		)
		(fp_line
			(start -0.7874 0.4064)
			(end -0.7874 -0.4064)
			(stroke
				(width 0.1524)
				(type default)
			)
			(layer "F.SilkS")
		)
		(fp_line
			(start 0.7874 -0.4064)
			(end 0.7874 0.4064)
			(stroke
				(width 0.1524)
				(type default)
			)
			(layer "F.SilkS")
		)
		(fp_line
			(start 0.7874 0.4064)
			(end -0.7874 0.4064)
			(stroke
				(width 0.1524)
				(type default)
			)
			(layer "F.SilkS")
		)
		(fp_line
			(start -0.67945 -0.305054)
			(end -0.12065 -0.305054)
			(stroke
				(width 0.1)
				(type default)
			)
			(layer "F.Fab")
		)
		(fp_line
			(start -0.67945 0.3048)
			(end -0.67945 -0.305054)
			(stroke
				(width 0.1)
				(type default)
			)
			(layer "F.Fab")
		)
		(fp_line
			(start -0.12065 -0.305054)
			(end -0.12065 -0.2794)
			(stroke
				(width 0.1)
				(type default)
			)
			(layer "F.Fab")
		)
		(fp_line
			(start -0.12065 -0.2794)
			(end 0.12065 -0.2794)
			(stroke
				(width 0.1)
				(type default)
			)
			(layer "F.Fab")
		)
		(fp_line
			(start -0.12065 0.2794)
			(end -0.12065 0.3048)
			(stroke
				(width 0.1)
				(type default)
			)
			(layer "F.Fab")
		)
		(fp_line
			(start -0.12065 0.3048)
			(end -0.67945 0.3048)
			(stroke
				(width 0.1)
				(type default)
			)
			(layer "F.Fab")
		)
		(fp_line
			(start 0.120396 0.2794)
			(end -0.12065 0.2794)
			(stroke
				(width 0.1)
				(type default)
			)
			(layer "F.Fab")
		)
		(fp_line
			(start 0.120396 0.3048)
			(end 0.120396 0.2794)
			(stroke
				(width 0.1)
				(type default)
			)
			(layer "F.Fab")
		)
		(fp_line
			(start 0.12065 -0.3048)
			(end 0.67945 -0.3048)
			(stroke
				(width 0.1)
				(type default)
			)
			(layer "F.Fab")
		)
		(fp_line
			(start 0.12065 -0.2794)
			(end 0.12065 -0.3048)
			(stroke
				(width 0.1)
				(type default)
			)
			(layer "F.Fab")
		)
		(fp_line
			(start 0.67945 -0.3048)
			(end 0.67945 0.3048)
			(stroke
				(width 0.1)
				(type default)
			)
			(layer "F.Fab")
		)
		(fp_line
			(start 0.67945 0.3048)
			(end 0.120396 0.3048)
			(stroke
				(width 0.1)
				(type default)
			)
			(layer "F.Fab")
		)
		(pad "1" smd circle
			(at -0.40005 0)
			(size 0 0)
			(layers "F.Cu" "F.Mask" "F.Paste")
			(net "FAN_4_PWM_IL_R")
		)
		(pad "2" smd circle
			(at 0.40005 0)
			(size 0 0)
			(layers "F.Cu" "F.Mask" "F.Paste")
			(net "GND")
		)
	)
	(footprint ""
		(layer "F.Cu")
		(at 35.306 -119.564912 180)
		(property "Reference" "C2040"
			(at 0 0 180)
			(layer "F.SilkS")
			(hide yes)
			(effects
				(font
					(size 1.27 1.27)
				)
			)
		)
		(property "Value" ""
			(at 0 0 180)
			(layer "F.Fab")
			(effects
				(font
					(size 1.27 1.27)
				)
			)
		)
		(duplicate_pad_numbers_are_jumpers no)
		(fp_line
			(start 0.7874 0.4064)
			(end -0.7874 0.4064)
			(stroke
				(width 0.1524)
				(type default)
			)
			(layer "F.SilkS")
		)
		(fp_line
			(start 0.7874 -0.4064)
			(end 0.7874 0.4064)
			(stroke
				(width 0.1524)
				(type default)
			)
			(layer "F.SilkS")
		)
		(fp_line
			(start -0.7874 0.4064)
			(end -0.7874 -0.4064)
			(stroke
				(width 0.1524)
				(type default)
			)
			(layer "F.SilkS")
		)
		(fp_line
			(start -0.7874 -0.4064)
			(end 0.7874 -0.4064)
			(stroke
				(width 0.1524)
				(type default)
			)
			(layer "F.SilkS")
		)
		(fp_line
			(start 0.67945 0.3048)
			(end 0.120396 0.3048)
			(stroke
				(width 0.1)
				(type default)
			)
			(layer "F.Fab")
		)
		(fp_line
			(start 0.67945 -0.3048)
			(end 0.67945 0.3048)
			(stroke
				(width 0.1)
				(type default)
			)
			(layer "F.Fab")
		)
		(fp_line
			(start 0.12065 -0.2794)
			(end 0.12065 -0.3048)
			(stroke
				(width 0.1)
				(type default)
			)
			(layer "F.Fab")
		)
		(fp_line
			(start 0.12065 -0.3048)
			(end 0.67945 -0.3048)
			(stroke
				(width 0.1)
				(type default)
			)
			(layer "F.Fab")
		)
		(fp_line
			(start 0.120396 0.3048)
			(end 0.120396 0.2794)
			(stroke
				(width 0.1)
				(type default)
			)
			(layer "F.Fab")
		)
		(fp_line
			(start 0.120396 0.2794)
			(end -0.12065 0.2794)
			(stroke
				(width 0.1)
				(type default)
			)
			(layer "F.Fab")
		)
		(fp_line
			(start -0.12065 0.3048)
			(end -0.67945 0.3048)
			(stroke
				(width 0.1)
				(type default)
			)
			(layer "F.Fab")
		)
		(fp_line
			(start -0.12065 0.2794)
			(end -0.12065 0.3048)
			(stroke
				(width 0.1)
				(type default)
			)
			(layer "F.Fab")
		)
		(fp_line
			(start -0.12065 -0.2794)
			(end 0.12065 -0.2794)
			(stroke
				(width 0.1)
				(type default)
			)
			(layer "F.Fab")
		)
		(fp_line
			(start -0.12065 -0.305054)
			(end -0.12065 -0.2794)
			(stroke
				(width 0.1)
				(type default)
			)
			(layer "F.Fab")
		)
		(fp_line
			(start -0.67945 0.3048)
			(end -0.67945 -0.305054)
			(stroke
				(width 0.1)
				(type default)
			)
			(layer "F.Fab")
		)
		(fp_line
			(start -0.67945 -0.305054)
			(end -0.12065 -0.305054)
			(stroke
				(width 0.1)
				(type default)
			)
			(layer "F.Fab")
		)
		(pad "1" smd circle
			(at -0.40005 0 180)
			(size 0 0)
			(layers "F.Cu" "F.Mask" "F.Paste")
			(net "FAN_2_PWM_OL_R")
		)
		(pad "2" smd circle
			(at 0.40005 0 180)
			(size 0 0)
			(layers "F.Cu" "F.Mask" "F.Paste")
			(net "GND")
		)
	)
	(footprint ""
		(layer "F.Cu")
		(at 28.956 -176.022 180)
		(property "Reference" "R5104"
			(at 0 0 180)
			(layer "F.SilkS")
			(hide yes)
			(effects
				(font
					(size 1.27 1.27)
				)
			)
		)
		(property "Value" ""
			(at 0 0 180)
			(layer "F.Fab")
			(effects
				(font
					(size 1.27 1.27)
				)
			)
		)
		(duplicate_pad_numbers_are_jumpers no)
		(fp_line
			(start 0.7874 0.4064)
			(end -0.7874 0.4064)
			(stroke
				(width 0.1524)
				(type default)
			)
			(layer "F.SilkS")
		)
		(fp_line
			(start 0.7874 -0.4064)
			(end 0.7874 0.4064)
			(stroke
				(width 0.1524)
				(type default)
			)
			(layer "F.SilkS")
		)
		(fp_line
			(start -0.7874 0.4064)
			(end -0.7874 -0.4064)
			(stroke
				(width 0.1524)
				(type default)
			)
			(layer "F.SilkS")
		)
		(fp_line
			(start -0.7874 -0.4064)
			(end 0.7874 -0.4064)
			(stroke
				(width 0.1524)
				(type default)
			)
			(layer "F.SilkS")
		)
		(fp_line
			(start 0.67945 0.3048)
			(end 0.120396 0.3048)
			(stroke
				(width 0.1)
				(type default)
			)
			(layer "F.Fab")
		)
		(fp_line
			(start 0.67945 -0.3048)
			(end 0.67945 0.3048)
			(stroke
				(width 0.1)
				(type default)
			)
			(layer "F.Fab")
		)
		(fp_line
			(start 0.12065 -0.2794)
			(end 0.12065 -0.3048)
			(stroke
				(width 0.1)
				(type default)
			)
			(layer "F.Fab")
		)
		(fp_line
			(start 0.12065 -0.3048)
			(end 0.67945 -0.3048)
			(stroke
				(width 0.1)
				(type default)
			)
			(layer "F.Fab")
		)
		(fp_line
			(start 0.120396 0.3048)
			(end 0.120396 0.2794)
			(stroke
				(width 0.1)
				(type default)
			)
			(layer "F.Fab")
		)
		(fp_line
			(start 0.120396 0.2794)
			(end -0.12065 0.2794)
			(stroke
				(width 0.1)
				(type default)
			)
			(layer "F.Fab")
		)
		(fp_line
			(start -0.12065 0.3048)
			(end -0.67945 0.3048)
			(stroke
				(width 0.1)
				(type default)
			)
			(layer "F.Fab")
		)
		(fp_line
			(start -0.12065 0.2794)
			(end -0.12065 0.3048)
			(stroke
				(width 0.1)
				(type default)
			)
			(layer "F.Fab")
		)
		(fp_line
			(start -0.12065 -0.2794)
			(end 0.12065 -0.2794)
			(stroke
				(width 0.1)
				(type default)
			)
			(layer "F.Fab")
		)
		(fp_line
			(start -0.12065 -0.305054)
			(end -0.12065 -0.2794)
			(stroke
				(width 0.1)
				(type default)
			)
			(layer "F.Fab")
		)
		(fp_line
			(start -0.67945 0.3048)
			(end -0.67945 -0.305054)
			(stroke
				(width 0.1)
				(type default)
			)
			(layer "F.Fab")
		)
		(fp_line
			(start -0.67945 -0.305054)
			(end -0.12065 -0.305054)
			(stroke
				(width 0.1)
				(type default)
			)
			(layer "F.Fab")
		)
		(pad "1" smd circle
			(at -0.40005 0 180)
			(size 0 0)
			(layers "F.Cu" "F.Mask" "F.Paste")
			(net "FAN_5_OK_LED")
		)
		(pad "2" smd circle
			(at 0.40005 0 180)
			(size 0 0)
			(layers "F.Cu" "F.Mask" "F.Paste")
			(net "FAN_5_OK_R_LED")
		)
	)
	(footprint ""
		(layer "F.Cu")
		(at 14.351 -207.264 180)
		(property "Reference" "R5372"
			(at 0 0 180)
			(layer "F.SilkS")
			(hide yes)
			(effects
				(font
					(size 1.27 1.27)
				)
			)
		)
		(property "Value" ""
			(at 0 0 180)
			(layer "F.Fab")
			(effects
				(font
					(size 1.27 1.27)
				)
			)
		)
		(duplicate_pad_numbers_are_jumpers no)
		(fp_line
			(start 0.7874 0.4064)
			(end -0.7874 0.4064)
			(stroke
				(width 0.1524)
				(type default)
			)
			(layer "F.SilkS")
		)
		(fp_line
			(start 0.7874 -0.4064)
			(end 0.7874 0.4064)
			(stroke
				(width 0.1524)
				(type default)
			)
			(layer "F.SilkS")
		)
		(fp_line
			(start -0.7874 0.4064)
			(end -0.7874 -0.4064)
			(stroke
				(width 0.1524)
				(type default)
			)
			(layer "F.SilkS")
		)
		(fp_line
			(start -0.7874 -0.4064)
			(end 0.7874 -0.4064)
			(stroke
				(width 0.1524)
				(type default)
			)
			(layer "F.SilkS")
		)
		(fp_line
			(start 0.67945 0.3048)
			(end 0.120396 0.3048)
			(stroke
				(width 0.1)
				(type default)
			)
			(layer "F.Fab")
		)
		(fp_line
			(start 0.67945 -0.3048)
			(end 0.67945 0.3048)
			(stroke
				(width 0.1)
				(type default)
			)
			(layer "F.Fab")
		)
		(fp_line
			(start 0.12065 -0.2794)
			(end 0.12065 -0.3048)
			(stroke
				(width 0.1)
				(type default)
			)
			(layer "F.Fab")
		)
		(fp_line
			(start 0.12065 -0.3048)
			(end 0.67945 -0.3048)
			(stroke
				(width 0.1)
				(type default)
			)
			(layer "F.Fab")
		)
		(fp_line
			(start 0.120396 0.3048)
			(end 0.120396 0.2794)
			(stroke
				(width 0.1)
				(type default)
			)
			(layer "F.Fab")
		)
		(fp_line
			(start 0.120396 0.2794)
			(end -0.12065 0.2794)
			(stroke
				(width 0.1)
				(type default)
			)
			(layer "F.Fab")
		)
		(fp_line
			(start -0.12065 0.3048)
			(end -0.67945 0.3048)
			(stroke
				(width 0.1)
				(type default)
			)
			(layer "F.Fab")
		)
		(fp_line
			(start -0.12065 0.2794)
			(end -0.12065 0.3048)
			(stroke
				(width 0.1)
				(type default)
			)
			(layer "F.Fab")
		)
		(fp_line
			(start -0.12065 -0.2794)
			(end 0.12065 -0.2794)
			(stroke
				(width 0.1)
				(type default)
			)
			(layer "F.Fab")
		)
		(fp_line
			(start -0.12065 -0.305054)
			(end -0.12065 -0.2794)
			(stroke
				(width 0.1)
				(type default)
			)
			(layer "F.Fab")
		)
		(fp_line
			(start -0.67945 0.3048)
			(end -0.67945 -0.305054)
			(stroke
				(width 0.1)
				(type default)
			)
			(layer "F.Fab")
		)
		(fp_line
			(start -0.67945 -0.305054)
			(end -0.12065 -0.305054)
			(stroke
				(width 0.1)
				(type default)
			)
			(layer "F.Fab")
		)
		(pad "1" smd rect
			(at -0.40005 0)
			(size 0.4572 0.508)
			(layers "F.Cu" "F.Mask" "F.Paste")
			(net "FAN_6_OK_LED_R_N")
		)
		(pad "2" smd rect
			(at 0.40005 0)
			(size 0.4572 0.508)
			(layers "F.Cu" "F.Mask" "F.Paste")
			(net "FAN_6_OK_R_LED_N")
		)
	)
)
